# S9S_MB_2U (Grand Teton) — schematic netlist excerpt (pin names and nets, part order shuffled) for the footprints in the layout excerpt that follows; sources: Cadence DE-HDL packaged netlist, KiCad conversion of 03242023_DA0F0TMBIJ0_F0T_Motherboard_J_brd_V01_OCP.brd

R1483  Q_RES  10K 1% EMPTY  pkg 0402LF  page 208 : A = P3V3_AUX ; B = FM_CK440Q_DEV_25M_EN
R596  Q_RES  0 5% CHIP  pkg 0402LF  page 241 : A = I3C_SPD_DDREFGH_CPU0_BMC_R_SDA ; B = I3C_SPD_DDREFGH_CPU0_BMC_SDA

(kicad_pcb
	(version 20260206)
	(generator "pcbnew")
	(generator_version "10.0")
	(general
		(thickness 1.6)
		(legacy_teardrops no)
	)
	(paper "A4")
	(title_block
		(title "03242023_DA0F0TMBIJ0_F0T_Motherboard_J_brd_V01_OCP.brd")
		(comment 1 "Grand Teton / footprints 4796-4797 of 6105")
	)
	(layers
		(0 "F.Cu" signal "TOP")
		(4 "In1.Cu" signal "GND")
		(6 "In2.Cu" signal "IN1")
		(8 "In3.Cu" signal "GND1")
		(10 "In4.Cu" signal "IN2")
		(12 "In5.Cu" signal "GND2")
		(14 "In6.Cu" signal "IN3")
		(16 "In7.Cu" signal "GND3")
		(18 "In8.Cu" signal "VCC")
		(20 "In9.Cu" signal "VCC1")
		(22 "In10.Cu" signal "GND4")
		(24 "In11.Cu" signal "IN4")
		(26 "In12.Cu" signal "GND5")
		(28 "In13.Cu" signal "IN5")
		(30 "In14.Cu" signal "GND6")
		(32 "In15.Cu" signal "IN6")
		(34 "In16.Cu" signal "GND7")
		(2 "B.Cu" signal "BOTTOM")
		(9 "F.Adhes" user "F.Adhesive")
		(11 "B.Adhes" user "B.Adhesive")
		(13 "F.Paste" user "Package Geometry/Pastemask Top")
		(15 "B.Paste" user "Package Geometry/Pastemask Bottom")
		(5 "F.SilkS" user "Ref Des/Silkscreen Top")
		(7 "B.SilkS" user "Ref Des/Silkscreen Bottom")
		(1 "F.Mask" user "Board Geometry/Soldermask Top")
		(3 "B.Mask" user "Board Geometry/Soldermask Bottom")
		(17 "Dwgs.User" user "User.Drawings")
		(19 "Cmts.User" user "User.Comments")
		(21 "Eco1.User" user "User.Eco1")
		(23 "Eco2.User" user "User.Eco2")
		(25 "Edge.Cuts" user "Board Geometry/Outline")
		(27 "Margin" user)
		(31 "F.CrtYd" user "Package Geometry/Place Bound Top")
		(29 "B.CrtYd" user "Package Geometry/Place Bound Bottom")
		(35 "F.Fab" user "Ref Des/Assembly Top")
		(33 "B.Fab" user "Ref Des/Assembly Bottom")
	)
	(footprint ""
		(layer "B.Cu")
		(at 250.000516 -105.256584 90)
		(property "Reference" "R1483"
			(at 0 0 90)
			(layer "B.SilkS")
			(hide yes)
			(effects
				(font
					(size 1.27 1.27)
				)
				(justify mirror)
			)
		)
		(property "Value" ""
			(at 0 0 90)
			(layer "B.Fab")
			(effects
				(font
					(size 1.27 1.27)
				)
				(justify mirror)
			)
		)
		(duplicate_pad_numbers_are_jumpers no)
		(fp_line
			(start 0.7874 -0.4064)
			(end -0.7874 -0.4064)
			(stroke
				(width 0.1524)
				(type default)
			)
			(layer "B.SilkS")
		)
		(fp_line
			(start -0.7874 -0.4064)
			(end -0.7874 0.4064)
			(stroke
				(width 0.1524)
				(type default)
			)
			(layer "B.SilkS")
		)
		(fp_line
			(start 0.7874 0.4064)
			(end 0.7874 -0.4064)
			(stroke
				(width 0.1524)
				(type default)
			)
			(layer "B.SilkS")
		)
		(fp_line
			(start -0.7874 0.4064)
			(end 0.7874 0.4064)
			(stroke
				(width 0.1524)
				(type default)
			)
			(layer "B.SilkS")
		)
		(fp_line
			(start 0.67945 -0.305054)
			(end 0.12065 -0.305054)
			(stroke
				(width 0.1)
				(type default)
			)
			(layer "B.Fab")
		)
		(fp_line
			(start 0.12065 -0.305054)
			(end 0.12065 -0.2794)
			(stroke
				(width 0.1)
				(type default)
			)
			(layer "B.Fab")
		)
		(fp_line
			(start -0.12065 -0.3048)
			(end -0.67945 -0.3048)
			(stroke
				(width 0.1)
				(type default)
			)
			(layer "B.Fab")
		)
		(fp_line
			(start -0.67945 -0.3048)
			(end -0.67945 0.3048)
			(stroke
				(width 0.1)
				(type default)
			)
			(layer "B.Fab")
		)
		(fp_line
			(start 0.12065 -0.2794)
			(end -0.12065 -0.2794)
			(stroke
				(width 0.1)
				(type default)
			)
			(layer "B.Fab")
		)
		(fp_line
			(start -0.12065 -0.2794)
			(end -0.12065 -0.3048)
			(stroke
				(width 0.1)
				(type default)
			)
			(layer "B.Fab")
		)
		(fp_line
			(start 0.12065 0.2794)
			(end 0.12065 0.3048)
			(stroke
				(width 0.1)
				(type default)
			)
			(layer "B.Fab")
		)
		(fp_line
			(start -0.120396 0.2794)
			(end 0.12065 0.2794)
			(stroke
				(width 0.1)
				(type default)
			)
			(layer "B.Fab")
		)
		(fp_line
			(start 0.67945 0.3048)
			(end 0.67945 -0.305054)
			(stroke
				(width 0.1)
				(type default)
			)
			(layer "B.Fab")
		)
		(fp_line
			(start 0.12065 0.3048)
			(end 0.67945 0.3048)
			(stroke
				(width 0.1)
				(type default)
			)
			(layer "B.Fab")
		)
		(fp_line
			(start -0.120396 0.3048)
			(end -0.120396 0.2794)
			(stroke
				(width 0.1)
				(type default)
			)
			(layer "B.Fab")
		)
		(fp_line
			(start -0.67945 0.3048)
			(end -0.120396 0.3048)
			(stroke
				(width 0.1)
				(type default)
			)
			(layer "B.Fab")
		)
		(pad "1" smd circle
			(at 0.40005 0 270)
			(size 0 0)
			(layers "B.Cu" "B.Mask" "B.Paste")
			(net "P3V3_AUX")
		)
		(pad "2" smd circle
			(at -0.40005 0 270)
			(size 0 0)
			(layers "B.Cu" "B.Mask" "B.Paste")
			(net "FM_CK440Q_DEV_25M_EN")
		)
	)
	(footprint ""
		(layer "B.Cu")
		(at 187.34913 -13.60043 -90)
		(property "Reference" "R596"
			(at 0 0 90)
			(layer "B.SilkS")
			(hide yes)
			(effects
				(font
					(size 1.27 1.27)
				)
				(justify mirror)
			)
		)
		(property "Value" ""
			(at 0 0 90)
			(layer "B.Fab")
			(effects
				(font
					(size 1.27 1.27)
				)
				(justify mirror)
			)
		)
		(duplicate_pad_numbers_are_jumpers no)
		(fp_line
			(start -0.7874 0.4064)
			(end 0.7874 0.4064)
			(stroke
				(width 0.1524)
				(type default)
			)
			(layer "B.SilkS")
		)
		(fp_line
			(start 0.7874 0.4064)
			(end 0.7874 -0.4064)
			(stroke
				(width 0.1524)
				(type default)
			)
			(layer "B.SilkS")
		)
		(fp_line
			(start -0.7874 -0.4064)
			(end -0.7874 0.4064)
			(stroke
				(width 0.1524)
				(type default)
			)
			(layer "B.SilkS")
		)
		(fp_line
			(start 0.7874 -0.4064)
			(end -0.7874 -0.4064)
			(stroke
				(width 0.1524)
				(type default)
			)
			(layer "B.SilkS")
		)
		(fp_line
			(start -0.67945 0.3048)
			(end -0.120396 0.3048)
			(stroke
				(width 0.1)
				(type default)
			)
			(layer "B.Fab")
		)
		(fp_line
			(start -0.120396 0.3048)
			(end -0.120396 0.2794)
			(stroke
				(width 0.1)
				(type default)
			)
			(layer "B.Fab")
		)
		(fp_line
			(start 0.12065 0.3048)
			(end 0.67945 0.3048)
			(stroke
				(width 0.1)
				(type default)
			)
			(layer "B.Fab")
		)
		(fp_line
			(start 0.67945 0.3048)
			(end 0.67945 -0.305054)
			(stroke
				(width 0.1)
				(type default)
			)
			(layer "B.Fab")
		)
		(fp_line
			(start -0.120396 0.2794)
			(end 0.12065 0.2794)
			(stroke
				(width 0.1)
				(type default)
			)
			(layer "B.Fab")
		)
		(fp_line
			(start 0.12065 0.2794)
			(end 0.12065 0.3048)
			(stroke
				(width 0.1)
				(type default)
			)
			(layer "B.Fab")
		)
		(fp_line
			(start -0.12065 -0.2794)
			(end -0.12065 -0.3048)
			(stroke
				(width 0.1)
				(type default)
			)
			(layer "B.Fab")
		)
		(fp_line
			(start 0.12065 -0.2794)
			(end -0.12065 -0.2794)
			(stroke
				(width 0.1)
				(type default)
			)
			(layer "B.Fab")
		)
		(fp_line
			(start -0.67945 -0.3048)
			(end -0.67945 0.3048)
			(stroke
				(width 0.1)
				(type default)
			)
			(layer "B.Fab")
		)
		(fp_line
			(start -0.12065 -0.3048)
			(end -0.67945 -0.3048)
			(stroke
				(width 0.1)
				(type default)
			)
			(layer "B.Fab")
		)
		(fp_line
			(start 0.12065 -0.305054)
			(end 0.12065 -0.2794)
			(stroke
				(width 0.1)
				(type default)
			)
			(layer "B.Fab")
		)
		(fp_line
			(start 0.67945 -0.305054)
			(end 0.12065 -0.305054)
			(stroke
				(width 0.1)
				(type default)
			)
			(layer "B.Fab")
		)
		(pad "1" smd circle
			(at 0.40005 0 90)
			(size 0 0)
			(layers "B.Cu" "B.Mask" "B.Paste")
			(net "I3C_SPD_DDREFGH_CPU0_BMC_R_SDA")
		)
		(pad "2" smd circle
			(at -0.40005 0 90)
			(size 0 0)
			(layers "B.Cu" "B.Mask" "B.Paste")
			(net "I3C_SPD_DDREFGH_CPU0_BMC_SDA")
		)
	)
)
